(kicad_pcb
	(version 20260206)
	(generator "pcbnew")
	(generator_version "10.0")
	(general
		(thickness 1.6)
		(legacy_teardrops no)
	)
	(paper "A4")
	(title_block
		(title "01162023_DA0F0TEBIF0_F0T_Expander_BD_F_brd_V02_OCP.brd")
		(comment 1 "Grand Teton / footprints 6144-6150 of 9728")
	)
	(layers
		(0 "F.Cu" signal "TOP")
		(4 "In1.Cu" signal "GND")
		(6 "In2.Cu" signal "VCC")
		(8 "In3.Cu" signal "VCC1")
		(10 "In4.Cu" signal "GND1")
		(12 "In5.Cu" signal "IN1")
		(14 "In6.Cu" signal "GND2")
		(16 "In7.Cu" signal "IN2")
		(18 "In8.Cu" signal "GND3")
		(20 "In9.Cu" signal "IN3")
		(22 "In10.Cu" signal "GND4")
		(24 "In11.Cu" signal "IN4")
		(26 "In12.Cu" signal "GND5")
		(28 "In13.Cu" signal "IN5")
		(30 "In14.Cu" signal "GND6")
		(32 "In15.Cu" signal "IN6")
		(34 "In16.Cu" signal "GND7")
		(2 "B.Cu" signal "BOTTOM")
		(9 "F.Adhes" user "F.Adhesive")
		(11 "B.Adhes" user "B.Adhesive")
		(13 "F.Paste" user "Package Geometry/Pastemask Top")
		(15 "B.Paste" user "Package Geometry/Pastemask Bottom")
		(5 "F.SilkS" user "Ref Des/Silkscreen Top")
		(7 "B.SilkS" user "Ref Des/Silkscreen Bottom")
		(1 "F.Mask" user "Board Geometry/Soldermask Top")
		(3 "B.Mask" user "Board Geometry/Soldermask Bottom")
		(17 "Dwgs.User" user "User.Drawings")
		(19 "Cmts.User" user "User.Comments")
		(21 "Eco1.User" user "User.Eco1")
		(23 "Eco2.User" user "User.Eco2")
		(25 "Edge.Cuts" user "Board Geometry/Outline")
		(27 "Margin" user)
		(31 "F.CrtYd" user "Package Geometry/Place Bound Top")
		(29 "B.CrtYd" user "Package Geometry/Place Bound Bottom")
		(35 "F.Fab" user "Ref Des/Assembly Top")
		(33 "B.Fab" user "Ref Des/Assembly Bottom")
	)
	(footprint ""
		(layer "F.Cu")
		(at 249.051572 -124.120656 -90)
		(property "Reference" "PC454"
			(at 0 0 270)
			(layer "F.SilkS")
			(hide yes)
			(effects
				(font
					(size 1.27 1.27)
				)
			)
		)
		(property "Value" ""
			(at 0 0 270)
			(layer "F.Fab")
			(effects
				(font
					(size 1.27 1.27)
				)
			)
		)
		(duplicate_pad_numbers_are_jumpers no)
		(fp_line
			(start -0.7874 0.4064)
			(end -0.7874 -0.4064)
			(stroke
				(width 0.1524)
				(type default)
			)
			(layer "F.SilkS")
		)
		(fp_line
			(start 0.7874 0.4064)
			(end -0.7874 0.4064)
			(stroke
				(width 0.1524)
				(type default)
			)
			(layer "F.SilkS")
		)
		(fp_line
			(start -0.7874 -0.4064)
			(end 0.7874 -0.4064)
			(stroke
				(width 0.1524)
				(type default)
			)
			(layer "F.SilkS")
		)
		(fp_line
			(start 0.7874 -0.4064)
			(end 0.7874 0.4064)
			(stroke
				(width 0.1524)
				(type default)
			)
			(layer "F.SilkS")
		)
		(fp_line
			(start -0.67945 0.3048)
			(end -0.67945 -0.305054)
			(stroke
				(width 0.1)
				(type default)
			)
			(layer "F.Fab")
		)
		(fp_line
			(start -0.12065 0.3048)
			(end -0.67945 0.3048)
			(stroke
				(width 0.1)
				(type default)
			)
			(layer "F.Fab")
		)
		(fp_line
			(start 0.120396 0.3048)
			(end 0.120396 0.2794)
			(stroke
				(width 0.1)
				(type default)
			)
			(layer "F.Fab")
		)
		(fp_line
			(start 0.67945 0.3048)
			(end 0.120396 0.3048)
			(stroke
				(width 0.1)
				(type default)
			)
			(layer "F.Fab")
		)
		(fp_line
			(start -0.12065 0.2794)
			(end -0.12065 0.3048)
			(stroke
				(width 0.1)
				(type default)
			)
			(layer "F.Fab")
		)
		(fp_line
			(start 0.120396 0.2794)
			(end -0.12065 0.2794)
			(stroke
				(width 0.1)
				(type default)
			)
			(layer "F.Fab")
		)
		(fp_line
			(start -0.12065 -0.2794)
			(end 0.12065 -0.2794)
			(stroke
				(width 0.1)
				(type default)
			)
			(layer "F.Fab")
		)
		(fp_line
			(start 0.12065 -0.2794)
			(end 0.12065 -0.3048)
			(stroke
				(width 0.1)
				(type default)
			)
			(layer "F.Fab")
		)
		(fp_line
			(start 0.12065 -0.3048)
			(end 0.67945 -0.3048)
			(stroke
				(width 0.1)
				(type default)
			)
			(layer "F.Fab")
		)
		(fp_line
			(start 0.67945 -0.3048)
			(end 0.67945 0.3048)
			(stroke
				(width 0.1)
				(type default)
			)
			(layer "F.Fab")
		)
		(fp_line
			(start -0.67945 -0.305054)
			(end -0.12065 -0.305054)
			(stroke
				(width 0.1)
				(type default)
			)
			(layer "F.Fab")
		)
		(fp_line
			(start -0.12065 -0.305054)
			(end -0.12065 -0.2794)
			(stroke
				(width 0.1)
				(type default)
			)
			(layer "F.Fab")
		)
		(pad "1" smd circle
			(at -0.40005 0 270)
			(size 0 0)
			(layers "F.Cu" "F.Mask" "F.Paste")
			(net "P3V3_NIC4")
		)
		(pad "2" smd circle
			(at 0.40005 0 270)
			(size 0 0)
			(layers "F.Cu" "F.Mask" "F.Paste")
			(net "GND")
		)
	)
	(footprint ""
		(layer "F.Cu")
		(at 430.961546 -124.991114 180)
		(property "Reference" "C658"
			(at 0 0 180)
			(layer "F.SilkS")
			(hide yes)
			(effects
				(font
					(size 1.27 1.27)
				)
			)
		)
		(property "Value" ""
			(at 0 0 180)
			(layer "F.Fab")
			(effects
				(font
					(size 1.27 1.27)
				)
			)
		)
		(duplicate_pad_numbers_are_jumpers no)
		(fp_line
			(start 0.299974 0.150114)
			(end -0.299974 0.150114)
			(stroke
				(width 0.1)
				(type default)
			)
			(layer "F.Fab")
		)
		(fp_line
			(start 0.299974 -0.150114)
			(end 0.299974 0.150114)
			(stroke
				(width 0.1)
				(type default)
			)
			(layer "F.Fab")
		)
		(fp_line
			(start -0.299974 0.150114)
			(end -0.299974 -0.150114)
			(stroke
				(width 0.1)
				(type default)
			)
			(layer "F.Fab")
		)
		(fp_line
			(start -0.299974 -0.150114)
			(end 0.299974 -0.150114)
			(stroke
				(width 0.1)
				(type default)
			)
			(layer "F.Fab")
		)
		(pad "1" smd rect
			(at -0.2667 0 180)
			(size 0.3048 0.381)
			(layers "F.Cu" "F.Mask" "F.Paste")
			(net "P5E_PEX3_STN0_TX_DP<3>")
		)
		(pad "2" smd rect
			(at 0.2667 0 180)
			(size 0.3048 0.381)
			(layers "F.Cu" "F.Mask" "F.Paste")
			(net "P5E_PEX3_STN0_TX_C_DP<3>")
		)
	)
	(footprint ""
		(layer "F.Cu")
		(at 19.24685 -37.47516)
		(property "Reference" "R5875"
			(at 0 0 0)
			(layer "F.SilkS")
			(hide yes)
			(effects
				(font
					(size 1.27 1.27)
				)
			)
		)
		(property "Value" ""
			(at 0 0 0)
			(layer "F.Fab")
			(effects
				(font
					(size 1.27 1.27)
				)
			)
		)
		(duplicate_pad_numbers_are_jumpers no)
		(fp_line
			(start -0.7874 -0.4064)
			(end 0.7874 -0.4064)
			(stroke
				(width 0.1524)
				(type default)
			)
			(layer "F.SilkS")
		)
		(fp_line
			(start -0.7874 0.4064)
			(end -0.7874 -0.4064)
			(stroke
				(width 0.1524)
				(type default)
			)
			(layer "F.SilkS")
		)
		(fp_line
			(start 0.7874 -0.4064)
			(end 0.7874 0.4064)
			(stroke
				(width 0.1524)
				(type default)
			)
			(layer "F.SilkS")
		)
		(fp_line
			(start 0.7874 0.4064)
			(end -0.7874 0.4064)
			(stroke
				(width 0.1524)
				(type default)
			)
			(layer "F.SilkS")
		)
		(fp_line
			(start -0.67945 -0.305054)
			(end -0.12065 -0.305054)
			(stroke
				(width 0.1)
				(type default)
			)
			(layer "F.Fab")
		)
		(fp_line
			(start -0.67945 0.3048)
			(end -0.67945 -0.305054)
			(stroke
				(width 0.1)
				(type default)
			)
			(layer "F.Fab")
		)
		(fp_line
			(start -0.12065 -0.305054)
			(end -0.12065 -0.2794)
			(stroke
				(width 0.1)
				(type default)
			)
			(layer "F.Fab")
		)
		(fp_line
			(start -0.12065 -0.2794)
			(end 0.12065 -0.2794)
			(stroke
				(width 0.1)
				(type default)
			)
			(layer "F.Fab")
		)
		(fp_line
			(start -0.12065 0.2794)
			(end -0.12065 0.3048)
			(stroke
				(width 0.1)
				(type default)
			)
			(layer "F.Fab")
		)
		(fp_line
			(start -0.12065 0.3048)
			(end -0.67945 0.3048)
			(stroke
				(width 0.1)
				(type default)
			)
			(layer "F.Fab")
		)
		(fp_line
			(start 0.120396 0.2794)
			(end -0.12065 0.2794)
			(stroke
				(width 0.1)
				(type default)
			)
			(layer "F.Fab")
		)
		(fp_line
			(start 0.120396 0.3048)
			(end 0.120396 0.2794)
			(stroke
				(width 0.1)
				(type default)
			)
			(layer "F.Fab")
		)
		(fp_line
			(start 0.12065 -0.3048)
			(end 0.67945 -0.3048)
			(stroke
				(width 0.1)
				(type default)
			)
			(layer "F.Fab")
		)
		(fp_line
			(start 0.12065 -0.2794)
			(end 0.12065 -0.3048)
			(stroke
				(width 0.1)
				(type default)
			)
			(layer "F.Fab")
		)
		(fp_line
			(start 0.67945 -0.3048)
			(end 0.67945 0.3048)
			(stroke
				(width 0.1)
				(type default)
			)
			(layer "F.Fab")
		)
		(fp_line
			(start 0.67945 0.3048)
			(end 0.120396 0.3048)
			(stroke
				(width 0.1)
				(type default)
			)
			(layer "F.Fab")
		)
		(pad "1" smd circle
			(at -0.40005 0)
			(size 0 0)
			(layers "F.Cu" "F.Mask" "F.Paste")
			(net "P3V3_SSD1")
		)
		(pad "2" smd circle
			(at 0.40005 0)
			(size 0 0)
			(layers "F.Cu" "F.Mask" "F.Paste")
			(net "P3V3_SSD1_PG_G1")
		)
	)
	(footprint ""
		(layer "F.Cu")
		(at 69.792342 -32.739584 180)
		(property "Reference" "C83"
			(at 0 0 180)
			(layer "F.SilkS")
			(hide yes)
			(effects
				(font
					(size 1.27 1.27)
				)
			)
		)
		(property "Value" ""
			(at 0 0 180)
			(layer "F.Fab")
			(effects
				(font
					(size 1.27 1.27)
				)
			)
		)
		(duplicate_pad_numbers_are_jumpers no)
		(fp_line
			(start 0.299974 0.150114)
			(end -0.299974 0.150114)
			(stroke
				(width 0.1)
				(type default)
			)
			(layer "F.Fab")
		)
		(fp_line
			(start 0.299974 -0.150114)
			(end 0.299974 0.150114)
			(stroke
				(width 0.1)
				(type default)
			)
			(layer "F.Fab")
		)
		(fp_line
			(start -0.299974 0.150114)
			(end -0.299974 -0.150114)
			(stroke
				(width 0.1)
				(type default)
			)
			(layer "F.Fab")
		)
		(fp_line
			(start -0.299974 -0.150114)
			(end 0.299974 -0.150114)
			(stroke
				(width 0.1)
				(type default)
			)
			(layer "F.Fab")
		)
		(pad "1" smd rect
			(at -0.2667 0 180)
			(size 0.3048 0.381)
			(layers "F.Cu" "F.Mask" "F.Paste")
			(net "P5E_PEX0_STN2_TX_DP<38>")
		)
		(pad "2" smd rect
			(at 0.2667 0 180)
			(size 0.3048 0.381)
			(layers "F.Cu" "F.Mask" "F.Paste")
			(net "P5E_PEX0_STN2_TX_C_DP<38>")
		)
	)
	(footprint ""
		(layer "F.Cu")
		(at 240.121948 -85.551518)
		(property "Reference" "R6286"
			(at 0 0 0)
			(layer "F.SilkS")
			(hide yes)
			(effects
				(font
					(size 1.27 1.27)
				)
			)
		)
		(property "Value" ""
			(at 0 0 0)
			(layer "F.Fab")
			(effects
				(font
					(size 1.27 1.27)
				)
			)
		)
		(duplicate_pad_numbers_are_jumpers no)
		(fp_line
			(start 0.003302 -0.4064)
			(end 0.7874 -0.4064)
			(stroke
				(width 0.1524)
				(type default)
			)
			(layer "F.SilkS")
		)
		(fp_line
			(start 0.7874 -0.4064)
			(end 0.7874 0.4064)
			(stroke
				(width 0.1524)
				(type default)
			)
			(layer "F.SilkS")
		)
		(fp_line
			(start 0.7874 0.4064)
			(end -0.7874 0.4064)
			(stroke
				(width 0.1524)
				(type default)
			)
			(layer "F.SilkS")
		)
		(fp_line
			(start -0.67945 -0.305054)
			(end -0.12065 -0.305054)
			(stroke
				(width 0.1)
				(type default)
			)
			(layer "F.Fab")
		)
		(fp_line
			(start -0.67945 0.3048)
			(end -0.67945 -0.305054)
			(stroke
				(width 0.1)
				(type default)
			)
			(layer "F.Fab")
		)
		(fp_line
			(start -0.12065 -0.305054)
			(end -0.12065 -0.2794)
			(stroke
				(width 0.1)
				(type default)
			)
			(layer "F.Fab")
		)
		(fp_line
			(start -0.12065 -0.2794)
			(end 0.12065 -0.2794)
			(stroke
				(width 0.1)
				(type default)
			)
			(layer "F.Fab")
		)
		(fp_line
			(start -0.12065 0.2794)
			(end -0.12065 0.3048)
			(stroke
				(width 0.1)
				(type default)
			)
			(layer "F.Fab")
		)
		(fp_line
			(start -0.12065 0.3048)
			(end -0.67945 0.3048)
			(stroke
				(width 0.1)
				(type default)
			)
			(layer "F.Fab")
		)
		(fp_line
			(start 0.120396 0.2794)
			(end -0.12065 0.2794)
			(stroke
				(width 0.1)
				(type default)
			)
			(layer "F.Fab")
		)
		(fp_line
			(start 0.120396 0.3048)
			(end 0.120396 0.2794)
			(stroke
				(width 0.1)
				(type default)
			)
			(layer "F.Fab")
		)
		(fp_line
			(start 0.12065 -0.3048)
			(end 0.67945 -0.3048)
			(stroke
				(width 0.1)
				(type default)
			)
			(layer "F.Fab")
		)
		(fp_line
			(start 0.12065 -0.2794)
			(end 0.12065 -0.3048)
			(stroke
				(width 0.1)
				(type default)
			)
			(layer "F.Fab")
		)
		(fp_line
			(start 0.67945 -0.3048)
			(end 0.67945 0.3048)
			(stroke
				(width 0.1)
				(type default)
			)
			(layer "F.Fab")
		)
		(fp_line
			(start 0.67945 0.3048)
			(end 0.120396 0.3048)
			(stroke
				(width 0.1)
				(type default)
			)
			(layer "F.Fab")
		)
		(pad "1" smd rect
			(at -0.40005 0 180)
			(size 0.4572 0.508)
			(layers "F.Cu" "F.Mask" "F.Paste")
			(net "USB2_FT4232_CLI_DP")
		)
		(pad "2" smd rect
			(at 0.40005 0 180)
			(size 0.4572 0.508)
			(layers "F.Cu" "F.Mask" "F.Paste")
			(net "GND")
		)
	)
	(footprint ""
		(layer "F.Cu")
		(at 251.423678 -152.71115 90)
		(property "Reference" "R730"
			(at 0 0 90)
			(layer "F.SilkS")
			(hide yes)
			(effects
				(font
					(size 1.27 1.27)
				)
			)
		)
		(property "Value" ""
			(at 0 0 90)
			(layer "F.Fab")
			(effects
				(font
					(size 1.27 1.27)
				)
			)
		)
		(duplicate_pad_numbers_are_jumpers no)
		(fp_line
			(start 0.7874 -0.4064)
			(end 0.7874 0.4064)
			(stroke
				(width 0.1524)
				(type default)
			)
			(layer "F.SilkS")
		)
		(fp_line
			(start -0.7874 -0.4064)
			(end 0.7874 -0.4064)
			(stroke
				(width 0.1524)
				(type default)
			)
			(layer "F.SilkS")
		)
		(fp_line
			(start 0.7874 0.4064)
			(end -0.7874 0.4064)
			(stroke
				(width 0.1524)
				(type default)
			)
			(layer "F.SilkS")
		)
		(fp_line
			(start -0.7874 0.4064)
			(end -0.7874 -0.4064)
			(stroke
				(width 0.1524)
				(type default)
			)
			(layer "F.SilkS")
		)
		(fp_line
			(start -0.12065 -0.305054)
			(end -0.12065 -0.2794)
			(stroke
				(width 0.1)
				(type default)
			)
			(layer "F.Fab")
		)
		(fp_line
			(start -0.67945 -0.305054)
			(end -0.12065 -0.305054)
			(stroke
				(width 0.1)
				(type default)
			)
			(layer "F.Fab")
		)
		(fp_line
			(start 0.67945 -0.3048)
			(end 0.67945 0.3048)
			(stroke
				(width 0.1)
				(type default)
			)
			(layer "F.Fab")
		)
		(fp_line
			(start 0.12065 -0.3048)
			(end 0.67945 -0.3048)
			(stroke
				(width 0.1)
				(type default)
			)
			(layer "F.Fab")
		)
		(fp_line
			(start 0.12065 -0.2794)
			(end 0.12065 -0.3048)
			(stroke
				(width 0.1)
				(type default)
			)
			(layer "F.Fab")
		)
		(fp_line
			(start -0.12065 -0.2794)
			(end 0.12065 -0.2794)
			(stroke
				(width 0.1)
				(type default)
			)
			(layer "F.Fab")
		)
		(fp_line
			(start 0.120396 0.2794)
			(end -0.12065 0.2794)
			(stroke
				(width 0.1)
				(type default)
			)
			(layer "F.Fab")
		)
		(fp_line
			(start -0.12065 0.2794)
			(end -0.12065 0.3048)
			(stroke
				(width 0.1)
				(type default)
			)
			(layer "F.Fab")
		)
		(fp_line
			(start 0.67945 0.3048)
			(end 0.120396 0.3048)
			(stroke
				(width 0.1)
				(type default)
			)
			(layer "F.Fab")
		)
		(fp_line
			(start 0.120396 0.3048)
			(end 0.120396 0.2794)
			(stroke
				(width 0.1)
				(type default)
			)
			(layer "F.Fab")
		)
		(fp_line
			(start -0.12065 0.3048)
			(end -0.67945 0.3048)
			(stroke
				(width 0.1)
				(type default)
			)
			(layer "F.Fab")
		)
		(fp_line
			(start -0.67945 0.3048)
			(end -0.67945 -0.305054)
			(stroke
				(width 0.1)
				(type default)
			)
			(layer "F.Fab")
		)
		(pad "1" smd circle
			(at -0.40005 0 90)
			(size 0 0)
			(layers "F.Cu" "F.Mask" "F.Paste")
			(net "NIC4_ADC_A0")
		)
		(pad "2" smd circle
			(at 0.40005 0 90)
			(size 0 0)
			(layers "F.Cu" "F.Mask" "F.Paste")
			(net "GND")
		)
	)
	(footprint ""
		(layer "F.Cu")
		(at 258.46786 -56.353456)
		(property "Reference" "C2869"
			(at 0 0 0)
			(layer "F.SilkS")
			(hide yes)
			(effects
				(font
					(size 1.27 1.27)
				)
			)
		)
		(property "Value" ""
			(at 0 0 0)
			(layer "F.Fab")
			(effects
				(font
					(size 1.27 1.27)
				)
			)
		)
		(duplicate_pad_numbers_are_jumpers no)
		(fp_line
			(start -0.7874 -0.4064)
			(end 0.7874 -0.4064)
			(stroke
				(width 0.1524)
				(type default)
			)
			(layer "F.SilkS")
		)
		(fp_line
			(start -0.7874 0.4064)
			(end -0.7874 -0.4064)
			(stroke
				(width 0.1524)
				(type default)
			)
			(layer "F.SilkS")
		)
		(fp_line
			(start 0.7874 -0.4064)
			(end 0.7874 0.4064)
			(stroke
				(width 0.1524)
				(type default)
			)
			(layer "F.SilkS")
		)
		(fp_line
			(start 0.7874 0.4064)
			(end -0.7874 0.4064)
			(stroke
				(width 0.1524)
				(type default)
			)
			(layer "F.SilkS")
		)
		(fp_line
			(start -0.67945 -0.305054)
			(end -0.12065 -0.305054)
			(stroke
				(width 0.1)
				(type default)
			)
			(layer "F.Fab")
		)
		(fp_line
			(start -0.67945 0.3048)
			(end -0.67945 -0.305054)
			(stroke
				(width 0.1)
				(type default)
			)
			(layer "F.Fab")
		)
		(fp_line
			(start -0.12065 -0.305054)
			(end -0.12065 -0.2794)
			(stroke
				(width 0.1)
				(type default)
			)
			(layer "F.Fab")
		)
		(fp_line
			(start -0.12065 -0.2794)
			(end 0.12065 -0.2794)
			(stroke
				(width 0.1)
				(type default)
			)
			(layer "F.Fab")
		)
		(fp_line
			(start -0.12065 0.2794)
			(end -0.12065 0.3048)
			(stroke
				(width 0.1)
				(type default)
			)
			(layer "F.Fab")
		)
		(fp_line
			(start -0.12065 0.3048)
			(end -0.67945 0.3048)
			(stroke
				(width 0.1)
				(type default)
			)
			(layer "F.Fab")
		)
		(fp_line
			(start 0.120396 0.2794)
			(end -0.12065 0.2794)
			(stroke
				(width 0.1)
				(type default)
			)
			(layer "F.Fab")
		)
		(fp_line
			(start 0.120396 0.3048)
			(end 0.120396 0.2794)
			(stroke
				(width 0.1)
				(type default)
			)
			(layer "F.Fab")
		)
		(fp_line
			(start 0.12065 -0.3048)
			(end 0.67945 -0.3048)
			(stroke
				(width 0.1)
				(type default)
			)
			(layer "F.Fab")
		)
		(fp_line
			(start 0.12065 -0.2794)
			(end 0.12065 -0.3048)
			(stroke
				(width 0.1)
				(type default)
			)
			(layer "F.Fab")
		)
		(fp_line
			(start 0.67945 -0.3048)
			(end 0.67945 0.3048)
			(stroke
				(width 0.1)
				(type default)
			)
			(layer "F.Fab")
		)
		(fp_line
			(start 0.67945 0.3048)
			(end 0.120396 0.3048)
			(stroke
				(width 0.1)
				(type default)
			)
			(layer "F.Fab")
		)
		(pad "1" smd circle
			(at -0.40005 0)
			(size 0 0)
			(layers "F.Cu" "F.Mask" "F.Paste")
			(net "SSD8_PWR_EN_R")
		)
		(pad "2" smd circle
			(at 0.40005 0)
			(size 0 0)
			(layers "F.Cu" "F.Mask" "F.Paste")
			(net "GND")
		)
	)
)
